# T6G (Grand Teton) — schematic netlist excerpt (pin names and nets, part order shuffled) for the footprints in the layout excerpt that follows; sources: Cadence DE-HDL packaged netlist, KiCad conversion of 04192023_DAF0TMB3IC0_F0TG_MB_C_brd_V02_OCP.brd

C1867  Q_CAP  10UF 25V 10% X6S  pkg C0805  page 111 : A = P3V3_AUX ; B = GND
C1033  Q_CAP  100UF 4V 20% X6S  pkg C0805  page 312 : A = P0V9_CPU0_RT3_2A ; B = GND
C480  Q_CAP  10UF 6.3V 20% X6S  pkg C0402  page 356 : A = P0V9_CPU1_RT3_2A ; B = GND

(kicad_pcb
	(version 20260206)
	(generator "pcbnew")
	(generator_version "10.0")
	(general
		(thickness 1.6)
		(legacy_teardrops no)
	)
	(paper "A4")
	(title_block
		(title "04192023_DAF0TMB3IC0_F0TG_MB_C_brd_V02_OCP.brd")
		(comment 1 "Grand Teton / footprints 5079-5081 of 8354")
	)
	(layers
		(0 "F.Cu" signal "TOP")
		(4 "In1.Cu" signal "GND")
		(6 "In2.Cu" signal "IN1")
		(8 "In3.Cu" signal "GND1")
		(10 "In4.Cu" signal "IN2")
		(12 "In5.Cu" signal "GND2")
		(14 "In6.Cu" signal "IN3")
		(16 "In7.Cu" signal "GND3")
		(18 "In8.Cu" signal "VCC")
		(20 "In9.Cu" signal "VCC1")
		(22 "In10.Cu" signal "GND4")
		(24 "In11.Cu" signal "IN4")
		(26 "In12.Cu" signal "GND5")
		(28 "In13.Cu" signal "IN5")
		(30 "In14.Cu" signal "GND6")
		(32 "In15.Cu" signal "IN6")
		(34 "In16.Cu" signal "GND7")
		(2 "B.Cu" signal "BOTTOM")
		(9 "F.Adhes" user "F.Adhesive")
		(11 "B.Adhes" user "B.Adhesive")
		(13 "F.Paste" user "Package Geometry/Pastemask Top")
		(15 "B.Paste" user "Package Geometry/Pastemask Bottom")
		(5 "F.SilkS" user "Ref Des/Silkscreen Top")
		(7 "B.SilkS" user "Ref Des/Silkscreen Bottom")
		(1 "F.Mask" user "Board Geometry/Soldermask Top")
		(3 "B.Mask" user "Board Geometry/Soldermask Bottom")
		(17 "Dwgs.User" user "User.Drawings")
		(19 "Cmts.User" user "User.Comments")
		(21 "Eco1.User" user "User.Eco1")
		(23 "Eco2.User" user "User.Eco2")
		(25 "Edge.Cuts" user "Board Geometry/Outline")
		(27 "Margin" user)
		(31 "F.CrtYd" user "Package Geometry/Place Bound Top")
		(29 "B.CrtYd" user "Package Geometry/Place Bound Bottom")
		(35 "F.Fab" user "Ref Des/Assembly Top")
		(33 "B.Fab" user "Ref Des/Assembly Bottom")
	)
	(footprint ""
		(layer "B.Cu")
		(at 365.512858 -397.228568)
		(property "Reference" "C1033"
			(at 0 0 0)
			(layer "B.SilkS")
			(hide yes)
			(effects
				(font
					(size 1.27 1.27)
				)
				(justify mirror)
			)
		)
		(property "Value" ""
			(at 0 0 0)
			(layer "B.Fab")
			(effects
				(font
					(size 1.27 1.27)
				)
				(justify mirror)
			)
		)
		(duplicate_pad_numbers_are_jumpers no)
		(fp_line
			(start -1.524 -0.762)
			(end -1.524 0.762)
			(stroke
				(width 0.1524)
				(type default)
			)
			(layer "B.SilkS")
		)
		(fp_line
			(start -1.524 0.762)
			(end 1.524 0.762)
			(stroke
				(width 0.1524)
				(type default)
			)
			(layer "B.SilkS")
		)
		(fp_line
			(start 1.524 -0.762)
			(end -1.524 -0.762)
			(stroke
				(width 0.1524)
				(type default)
			)
			(layer "B.SilkS")
		)
		(fp_line
			(start 1.524 0.762)
			(end 1.524 -0.762)
			(stroke
				(width 0.1524)
				(type default)
			)
			(layer "B.SilkS")
		)
		(fp_line
			(start -1.1049 -0.724916)
			(end 1.1049 -0.724916)
			(stroke
				(width 0.1)
				(type default)
			)
			(layer "B.Fab")
		)
		(fp_line
			(start -1.1049 0.724916)
			(end -1.1049 -0.724916)
			(stroke
				(width 0.1)
				(type default)
			)
			(layer "B.Fab")
		)
		(fp_line
			(start 1.1049 -0.724916)
			(end 1.1049 0.724916)
			(stroke
				(width 0.1)
				(type default)
			)
			(layer "B.Fab")
		)
		(fp_line
			(start 1.1049 0.724916)
			(end -1.1049 0.724916)
			(stroke
				(width 0.1)
				(type default)
			)
			(layer "B.Fab")
		)
		(pad "1" smd rect
			(at 0.889 0)
			(size 1.016 1.27)
			(layers "B.Cu" "B.Mask" "B.Paste")
			(net "P0V9_CPU0_RT3_2A")
		)
		(pad "2" smd rect
			(at -0.889 0)
			(size 1.016 1.27)
			(layers "B.Cu" "B.Mask" "B.Paste")
			(net "GND")
		)
	)
	(footprint ""
		(layer "B.Cu")
		(at 114.491008 -390.560052 90)
		(property "Reference" "C480"
			(at 0 0 90)
			(layer "B.SilkS")
			(hide yes)
			(effects
				(font
					(size 1.27 1.27)
				)
				(justify mirror)
			)
		)
		(property "Value" ""
			(at 0 0 90)
			(layer "B.Fab")
			(effects
				(font
					(size 1.27 1.27)
				)
				(justify mirror)
			)
		)
		(duplicate_pad_numbers_are_jumpers no)
		(fp_line
			(start 0.7874 -0.4064)
			(end -0.7874 -0.4064)
			(stroke
				(width 0.1524)
				(type default)
			)
			(layer "B.SilkS")
		)
		(fp_line
			(start -0.7874 -0.4064)
			(end -0.7874 0.4064)
			(stroke
				(width 0.1524)
				(type default)
			)
			(layer "B.SilkS")
		)
		(fp_line
			(start 0.7874 0.4064)
			(end 0.7874 -0.4064)
			(stroke
				(width 0.1524)
				(type default)
			)
			(layer "B.SilkS")
		)
		(fp_line
			(start -0.7874 0.4064)
			(end 0.7874 0.4064)
			(stroke
				(width 0.1524)
				(type default)
			)
			(layer "B.SilkS")
		)
		(fp_line
			(start 0.67945 -0.305054)
			(end 0.12065 -0.305054)
			(stroke
				(width 0.1)
				(type default)
			)
			(layer "B.Fab")
		)
		(fp_line
			(start 0.12065 -0.305054)
			(end 0.12065 -0.2794)
			(stroke
				(width 0.1)
				(type default)
			)
			(layer "B.Fab")
		)
		(fp_line
			(start -0.12065 -0.3048)
			(end -0.67945 -0.3048)
			(stroke
				(width 0.1)
				(type default)
			)
			(layer "B.Fab")
		)
		(fp_line
			(start -0.67945 -0.3048)
			(end -0.67945 0.3048)
			(stroke
				(width 0.1)
				(type default)
			)
			(layer "B.Fab")
		)
		(fp_line
			(start 0.12065 -0.2794)
			(end -0.12065 -0.2794)
			(stroke
				(width 0.1)
				(type default)
			)
			(layer "B.Fab")
		)
		(fp_line
			(start -0.12065 -0.2794)
			(end -0.12065 -0.3048)
			(stroke
				(width 0.1)
				(type default)
			)
			(layer "B.Fab")
		)
		(fp_line
			(start 0.12065 0.2794)
			(end 0.12065 0.3048)
			(stroke
				(width 0.1)
				(type default)
			)
			(layer "B.Fab")
		)
		(fp_line
			(start -0.120396 0.2794)
			(end 0.12065 0.2794)
			(stroke
				(width 0.1)
				(type default)
			)
			(layer "B.Fab")
		)
		(fp_line
			(start 0.67945 0.3048)
			(end 0.67945 -0.305054)
			(stroke
				(width 0.1)
				(type default)
			)
			(layer "B.Fab")
		)
		(fp_line
			(start 0.12065 0.3048)
			(end 0.67945 0.3048)
			(stroke
				(width 0.1)
				(type default)
			)
			(layer "B.Fab")
		)
		(fp_line
			(start -0.120396 0.3048)
			(end -0.120396 0.2794)
			(stroke
				(width 0.1)
				(type default)
			)
			(layer "B.Fab")
		)
		(fp_line
			(start -0.67945 0.3048)
			(end -0.120396 0.3048)
			(stroke
				(width 0.1)
				(type default)
			)
			(layer "B.Fab")
		)
		(pad "1" smd circle
			(at 0.40005 0 270)
			(size 0 0)
			(layers "B.Cu" "B.Mask" "B.Paste")
			(net "P0V9_CPU1_RT3_2A")
		)
		(pad "2" smd circle
			(at -0.40005 0 270)
			(size 0 0)
			(layers "B.Cu" "B.Mask" "B.Paste")
			(net "GND")
		)
	)
	(footprint ""
		(layer "B.Cu")
		(at 35.09899 -424.772582)
		(property "Reference" "C1867"
			(at 0 0 0)
			(layer "B.SilkS")
			(hide yes)
			(effects
				(font
					(size 1.27 1.27)
				)
				(justify mirror)
			)
		)
		(property "Value" ""
			(at 0 0 0)
			(layer "B.Fab")
			(effects
				(font
					(size 1.27 1.27)
				)
				(justify mirror)
			)
		)
		(duplicate_pad_numbers_are_jumpers no)
		(fp_line
			(start -1.524 -0.762)
			(end -1.524 0.762)
			(stroke
				(width 0.1524)
				(type default)
			)
			(layer "B.SilkS")
		)
		(fp_line
			(start -1.524 0.762)
			(end 1.524 0.762)
			(stroke
				(width 0.1524)
				(type default)
			)
			(layer "B.SilkS")
		)
		(fp_line
			(start 1.524 -0.762)
			(end -1.524 -0.762)
			(stroke
				(width 0.1524)
				(type default)
			)
			(layer "B.SilkS")
		)
		(fp_line
			(start 1.524 0.762)
			(end 1.524 -0.762)
			(stroke
				(width 0.1524)
				(type default)
			)
			(layer "B.SilkS")
		)
		(fp_line
			(start -1.1049 -0.724916)
			(end 1.1049 -0.724916)
			(stroke
				(width 0.1)
				(type default)
			)
			(layer "B.Fab")
		)
		(fp_line
			(start -1.1049 0.724916)
			(end -1.1049 -0.724916)
			(stroke
				(width 0.1)
				(type default)
			)
			(layer "B.Fab")
		)
		(fp_line
			(start 1.1049 -0.724916)
			(end 1.1049 0.724916)
			(stroke
				(width 0.1)
				(type default)
			)
			(layer "B.Fab")
		)
		(fp_line
			(start 1.1049 0.724916)
			(end -1.1049 0.724916)
			(stroke
				(width 0.1)
				(type default)
			)
			(layer "B.Fab")
		)
		(pad "1" smd rect
			(at 0.889 0)
			(size 1.016 1.27)
			(layers "B.Cu" "B.Mask" "B.Paste")
			(net "P3V3_AUX")
		)
		(pad "2" smd rect
			(at -0.889 0)
			(size 1.016 1.27)
			(layers "B.Cu" "B.Mask" "B.Paste")
			(net "GND")
		)
	)
)
